(kicad_pcb
	(version 20241229)
	(generator "pcbnew")
	(generator_version "9.0")
	(general
		(thickness 1.62)
		(legacy_teardrops no)
	)
	(paper "A3")
	(title_block
		(title "COM Express 7 Baseboard")
		(date "2025-02-04")
		(rev "1.1.2")
		(company "Antmicro Ltd")
		(comment 1 "www.antmicro.com")
		(comment 9 "footprint 486 of 802 (U45), pads 80-118 of 144")
	)
	(layers
		(0 "F.Cu" signal)
		(4 "In1.Cu" signal)
		(6 "In2.Cu" signal)
		(8 "In3.Cu" signal)
		(10 "In4.Cu" signal)
		(12 "In5.Cu" signal)
		(14 "In6.Cu" signal)
		(2 "B.Cu" signal)
		(9 "F.Adhes" user "F.Adhesive")
		(11 "B.Adhes" user "B.Adhesive")
		(13 "F.Paste" user)
		(15 "B.Paste" user)
		(5 "F.SilkS" user "F.Silkscreen")
		(7 "B.SilkS" user "B.Silkscreen")
		(1 "F.Mask" user)
		(3 "B.Mask" user)
		(17 "Dwgs.User" user "User.Drawings")
		(19 "Cmts.User" user "User.Comments")
		(21 "Eco1.User" user "User.Eco1")
		(23 "Eco2.User" user "User.Eco2")
		(25 "Edge.Cuts" user)
		(27 "Margin" user)
		(31 "F.CrtYd" user "F.Courtyard")
		(29 "B.CrtYd" user "B.Courtyard")
		(35 "F.Fab" user)
		(33 "B.Fab" user)
	)
	(footprint "antmicro-footprints:BGA-144_12x12_13.05x13.05mm_P1.0mm"
		(layer "F.Cu")
		(at 132.79 137.36 -90)
		(property "Reference" "U45"
			(at 7.9 4.85 180)
			(layer "F.SilkS")
			(effects
				(font
					(size 0.7 0.7)
					(thickness 0.15)
				)
				(justify right bottom)
			)
		)
		(property "Value" "TLK10232CTR"
			(at 0 7.525 90)
			(layer "F.Fab")
			(effects
				(font
					(size 0.7 0.7)
					(thickness 0.15)
				)
				(justify right bottom)
			)
		)
		(property "Datasheet" "https://www.ti.com/lit/ds/symlink/tlk10232.pdf?ts=1712150848075&ref_url=https%253A%252F%252Fwww.mouser.pl%252F"
			(at 0 0 270)
			(layer "F.Fab")
			(hide yes)
			(effects
				(font
					(size 1.27 1.27)
					(thickness 0.15)
				)
			)
		)
		(property "Author" "Antmicro"
			(at -4.57 270.15 0)
			(layer "F.Fab")
			(hide yes)
			(effects
				(font
					(size 1 1)
					(thickness 0.15)
				)
			)
		)
		(property "License" "Apache-2.0"
			(at -4.57 270.15 0)
			(layer "F.Fab")
			(hide yes)
			(effects
				(font
					(size 1 1)
					(thickness 0.15)
				)
			)
		)
		(property "MPN" "TLK10232CTR"
			(at -4.57 270.15 0)
			(layer "F.Fab")
			(hide yes)
			(effects
				(font
					(size 1 1)
					(thickness 0.15)
				)
			)
		)
		(property "Manufacturer" "Texas Instruments"
			(at -4.57 270.15 0)
			(layer "F.Fab")
			(hide yes)
			(effects
				(font
					(size 1 1)
					(thickness 0.15)
				)
			)
		)
		(sheetname "KR to SFI #2")
		(sheetfile "kr_sfi.kicad_sch")
		(attr smd)
		(pad "G8" smd circle
			(at 1.5 0.5 270)
			(size 0.5 0.5)
			(layers "F.Cu" "F.Mask" "F.Paste")
			(net 74 "+1V0")
			(pinfunction "DVDD")
			(pintype "passive")
			(solder_mask_margin 0.05)
			(teardrops
				(best_length_ratio 0.4)
				(max_length 1)
				(best_width_ratio 0.9)
				(max_width 2)
				(curved_edges yes)
				(filter_ratio 0.9)
				(enabled yes)
				(allow_two_segments yes)
				(prefer_zone_connections yes)
			)
		)
		(pad "G9" smd circle
			(at 2.5 0.5 270)
			(size 0.5 0.5)
			(layers "F.Cu" "F.Mask" "F.Paste")
			(net 677 "Net-(U45C-PRTAD1)")
			(pinfunction "PRTAD1")
			(pintype "input")
			(solder_mask_margin 0.05)
			(teardrops
				(best_length_ratio 0.4)
				(max_length 1)
				(best_width_ratio 0.9)
				(max_width 2)
				(curved_edges yes)
				(filter_ratio 0.9)
				(enabled yes)
				(allow_two_segments yes)
				(prefer_zone_connections yes)
			)
		)
		(pad "G10" smd circle
			(at 3.5 0.5 270)
			(size 0.5 0.5)
			(layers "F.Cu" "F.Mask" "F.Paste")
			(net 74 "+1V0")
			(pinfunction "VDDA_{LS/HS}")
			(pintype "passive")
			(solder_mask_margin 0.05)
			(teardrops
				(best_length_ratio 0.4)
				(max_length 1)
				(best_width_ratio 0.9)
				(max_width 2)
				(curved_edges yes)
				(filter_ratio 0.9)
				(enabled yes)
				(allow_two_segments yes)
				(prefer_zone_connections yes)
			)
		)
		(pad "G11" smd circle
			(at 4.5 0.5 270)
			(size 0.5 0.5)
			(layers "F.Cu" "F.Mask" "F.Paste")
			(net 1 "GND")
			(pinfunction "GND")
			(pintype "passive")
			(solder_mask_margin 0.05)
			(teardrops
				(best_length_ratio 0.4)
				(max_length 1)
				(best_width_ratio 0.9)
				(max_width 2)
				(curved_edges yes)
				(filter_ratio 0.9)
				(enabled yes)
				(allow_two_segments yes)
				(prefer_zone_connections yes)
			)
		)
		(pad "G12" smd circle
			(at 5.5 0.5 270)
			(size 0.5 0.5)
			(layers "F.Cu" "F.Mask" "F.Paste")
			(net 953 "/2xSFP+/KR to SFI #2/SFI_R.RX-")
			(pinfunction "HSRXB-")
			(pintype "input")
			(solder_mask_margin 0.05)
			(teardrops
				(best_length_ratio 0.4)
				(max_length 1)
				(best_width_ratio 0.9)
				(max_width 2)
				(curved_edges yes)
				(filter_ratio 0.9)
				(enabled yes)
				(allow_two_segments yes)
				(prefer_zone_connections yes)
			)
		)
		(pad "H1" smd circle
			(at -5.5 1.5 270)
			(size 0.5 0.5)
			(layers "F.Cu" "F.Mask" "F.Paste")
			(net 848 "unconnected-(U45B-INB0+-PadH1)")
			(pinfunction "INB0+")
			(pintype "input+no_connect")
			(solder_mask_margin 0.05)
			(teardrops
				(best_length_ratio 0.4)
				(max_length 1)
				(best_width_ratio 0.9)
				(max_width 2)
				(curved_edges yes)
				(filter_ratio 0.9)
				(enabled yes)
				(allow_two_segments yes)
				(prefer_zone_connections yes)
			)
		)
		(pad "H2" smd circle
			(at -4.5 1.5 270)
			(size 0.5 0.5)
			(layers "F.Cu" "F.Mask" "F.Paste")
			(net 1 "GND")
			(pinfunction "GND")
			(pintype "passive")
			(solder_mask_margin 0.05)
			(teardrops
				(best_length_ratio 0.4)
				(max_length 1)
				(best_width_ratio 0.9)
				(max_width 2)
				(curved_edges yes)
				(filter_ratio 0.9)
				(enabled yes)
				(allow_two_segments yes)
				(prefer_zone_connections yes)
			)
		)
		(pad "H3" smd circle
			(at -3.5 1.5 270)
			(size 0.5 0.5)
			(layers "F.Cu" "F.Mask" "F.Paste")
			(net 849 "unconnected-(U45B-OUTB0--PadH3)")
			(pinfunction "OUTB0-")
			(pintype "output+no_connect")
			(solder_mask_margin 0.05)
			(teardrops
				(best_length_ratio 0.4)
				(max_length 1)
				(best_width_ratio 0.9)
				(max_width 2)
				(curved_edges yes)
				(filter_ratio 0.9)
				(enabled yes)
				(allow_two_segments yes)
				(prefer_zone_connections yes)
			)
		)
		(pad "H4" smd circle
			(at -2.5 1.5 270)
			(size 0.5 0.5)
			(layers "F.Cu" "F.Mask" "F.Paste")
			(net 1 "GND")
			(pinfunction "GND")
			(pintype "passive")
			(solder_mask_margin 0.05)
			(teardrops
				(best_length_ratio 0.4)
				(max_length 1)
				(best_width_ratio 0.9)
				(max_width 2)
				(curved_edges yes)
				(filter_ratio 0.9)
				(enabled yes)
				(allow_two_segments yes)
				(prefer_zone_connections yes)
			)
		)
		(pad "H5" smd circle
			(at -1.5 1.5 270)
			(size 0.5 0.5)
			(layers "F.Cu" "F.Mask" "F.Paste")
			(net 143 "/2xSFP+/KR to SFI #2/~{RESET}")
			(pinfunction "~{RESET}")
			(pintype "input")
			(solder_mask_margin 0.05)
			(teardrops
				(best_length_ratio 0.4)
				(max_length 1)
				(best_width_ratio 0.9)
				(max_width 2)
				(curved_edges yes)
				(filter_ratio 0.9)
				(enabled yes)
				(allow_two_segments yes)
				(prefer_zone_connections yes)
			)
		)
		(pad "H6" smd circle
			(at -0.5 1.5 270)
			(size 0.5 0.5)
			(layers "F.Cu" "F.Mask" "F.Paste")
			(net 74 "+1V0")
			(pinfunction "VDDD")
			(pintype "passive")
			(solder_mask_margin 0.05)
			(teardrops
				(best_length_ratio 0.4)
				(max_length 1)
				(best_width_ratio 0.9)
				(max_width 2)
				(curved_edges yes)
				(filter_ratio 0.9)
				(enabled yes)
				(allow_two_segments yes)
				(prefer_zone_connections yes)
			)
		)
		(pad "H7" smd circle
			(at 0.5 1.5 270)
			(size 0.5 0.5)
			(layers "F.Cu" "F.Mask" "F.Paste")
			(net 74 "+1V0")
			(pinfunction "DVDD")
			(pintype "passive")
			(solder_mask_margin 0.05)
			(teardrops
				(best_length_ratio 0.4)
				(max_length 1)
				(best_width_ratio 0.9)
				(max_width 2)
				(curved_edges yes)
				(filter_ratio 0.9)
				(enabled yes)
				(allow_two_segments yes)
				(prefer_zone_connections yes)
			)
		)
		(pad "H8" smd circle
			(at 1.5 1.5 270)
			(size 0.5 0.5)
			(layers "F.Cu" "F.Mask" "F.Paste")
			(net 74 "+1V0")
			(pinfunction "VDDD")
			(pintype "passive")
			(solder_mask_margin 0.05)
			(teardrops
				(best_length_ratio 0.4)
				(max_length 1)
				(best_width_ratio 0.9)
				(max_width 2)
				(curved_edges yes)
				(filter_ratio 0.9)
				(enabled yes)
				(allow_two_segments yes)
				(prefer_zone_connections yes)
			)
		)
		(pad "H9" smd circle
			(at 2.5 1.5 270)
			(size 0.5 0.5)
			(layers "F.Cu" "F.Mask" "F.Paste")
			(net 759 "Net-(U45B-LS_OK_{OUT_B})")
			(pinfunction "LS_OK_{OUT_B}")
			(pintype "output")
			(solder_mask_margin 0.05)
			(teardrops
				(best_length_ratio 0.4)
				(max_length 1)
				(best_width_ratio 0.9)
				(max_width 2)
				(curved_edges yes)
				(filter_ratio 0.9)
				(enabled yes)
				(allow_two_segments yes)
				(prefer_zone_connections yes)
			)
		)
		(pad "H10" smd circle
			(at 3.5 1.5 270)
			(size 0.5 0.5)
			(layers "F.Cu" "F.Mask" "F.Paste")
			(net 683 "Net-(U45C-MODE_{SEL})")
			(pinfunction "MODE_{SEL}")
			(pintype "input")
			(solder_mask_margin 0.05)
			(teardrops
				(best_length_ratio 0.4)
				(max_length 1)
				(best_width_ratio 0.9)
				(max_width 2)
				(curved_edges yes)
				(filter_ratio 0.9)
				(enabled yes)
				(allow_two_segments yes)
				(prefer_zone_connections yes)
			)
		)
		(pad "H11" smd circle
			(at 4.5 1.5 270)
			(size 0.5 0.5)
			(layers "F.Cu" "F.Mask" "F.Paste")
			(net 1 "GND")
			(pinfunction "GND")
			(pintype "passive")
			(solder_mask_margin 0.05)
			(teardrops
				(best_length_ratio 0.4)
				(max_length 1)
				(best_width_ratio 0.9)
				(max_width 2)
				(curved_edges yes)
				(filter_ratio 0.9)
				(enabled yes)
				(allow_two_segments yes)
				(prefer_zone_connections yes)
			)
		)
		(pad "H12" smd circle
			(at 5.5 1.5 270)
			(size 0.5 0.5)
			(layers "F.Cu" "F.Mask" "F.Paste")
			(net 950 "/2xSFP+/KR to SFI #2/SFI_R.RX+")
			(pinfunction "HSRXB+")
			(pintype "input")
			(solder_mask_margin 0.05)
			(teardrops
				(best_length_ratio 0.4)
				(max_length 1)
				(best_width_ratio 0.9)
				(max_width 2)
				(curved_edges yes)
				(filter_ratio 0.9)
				(enabled yes)
				(allow_two_segments yes)
				(prefer_zone_connections yes)
			)
		)
		(pad "J1" smd circle
			(at -5.5 2.5 270)
			(size 0.5 0.5)
			(layers "F.Cu" "F.Mask" "F.Paste")
			(net 850 "unconnected-(U45B-INB0--PadJ1)")
			(pinfunction "INB0-")
			(pintype "input+no_connect")
			(solder_mask_margin 0.05)
			(teardrops
				(best_length_ratio 0.4)
				(max_length 1)
				(best_width_ratio 0.9)
				(max_width 2)
				(curved_edges yes)
				(filter_ratio 0.9)
				(enabled yes)
				(allow_two_segments yes)
				(prefer_zone_connections yes)
			)
		)
		(pad "J2" smd circle
			(at -4.5 2.5 270)
			(size 0.5 0.5)
			(layers "F.Cu" "F.Mask" "F.Paste")
			(net 74 "+1V0")
			(pinfunction "VDDA_{LS/HS}")
			(pintype "passive")
			(solder_mask_margin 0.05)
			(teardrops
				(best_length_ratio 0.4)
				(max_length 1)
				(best_width_ratio 0.9)
				(max_width 2)
				(curved_edges yes)
				(filter_ratio 0.9)
				(enabled yes)
				(allow_two_segments yes)
				(prefer_zone_connections yes)
			)
		)
		(pad "J3" smd circle
			(at -3.5 2.5 270)
			(size 0.5 0.5)
			(layers "F.Cu" "F.Mask" "F.Paste")
			(net 851 "unconnected-(U45B-OUTB0+-PadJ3)")
			(pinfunction "OUTB0+")
			(pintype "output+no_connect")
			(solder_mask_margin 0.05)
			(teardrops
				(best_length_ratio 0.4)
				(max_length 1)
				(best_width_ratio 0.9)
				(max_width 2)
				(curved_edges yes)
				(filter_ratio 0.9)
				(enabled yes)
				(allow_two_segments yes)
				(prefer_zone_connections yes)
			)
		)
		(pad "J4" smd circle
			(at -2.5 2.5 270)
			(size 0.5 0.5)
			(layers "F.Cu" "F.Mask" "F.Paste")
			(net 681 "Net-(U45B-~{PDTRXB})")
			(pinfunction "~{PDTRXB}")
			(pintype "input")
			(solder_mask_margin 0.05)
			(teardrops
				(best_length_ratio 0.4)
				(max_length 1)
				(best_width_ratio 0.9)
				(max_width 2)
				(curved_edges yes)
				(filter_ratio 0.9)
				(enabled yes)
				(allow_two_segments yes)
				(prefer_zone_connections yes)
			)
		)
		(pad "J5" smd circle
			(at -1.5 2.5 270)
			(size 0.5 0.5)
			(layers "F.Cu" "F.Mask" "F.Paste")
			(net 1 "GND")
			(pinfunction "GND")
			(pintype "passive")
			(solder_mask_margin 0.05)
			(teardrops
				(best_length_ratio 0.4)
				(max_length 1)
				(best_width_ratio 0.9)
				(max_width 2)
				(curved_edges yes)
				(filter_ratio 0.9)
				(enabled yes)
				(allow_two_segments yes)
				(prefer_zone_connections yes)
			)
		)
		(pad "J6" smd circle
			(at -0.5 2.5 270)
			(size 0.5 0.5)
			(layers "F.Cu" "F.Mask" "F.Paste")
			(net 680 "Net-(U45C-PRTAD3)")
			(pinfunction "PRTAD3")
			(pintype "input")
			(solder_mask_margin 0.05)
			(teardrops
				(best_length_ratio 0.4)
				(max_length 1)
				(best_width_ratio 0.9)
				(max_width 2)
				(curved_edges yes)
				(filter_ratio 0.9)
				(enabled yes)
				(allow_two_segments yes)
				(prefer_zone_connections yes)
			)
		)
		(pad "J7" smd circle
			(at 0.5 2.5 270)
			(size 0.5 0.5)
			(layers "F.Cu" "F.Mask" "F.Paste")
			(net 670 "/2xSFP+/KR to SFI #2/MDIO")
			(pinfunction "MDIO")
			(pintype "bidirectional")
			(solder_mask_margin 0.05)
			(teardrops
				(best_length_ratio 0.4)
				(max_length 1)
				(best_width_ratio 0.9)
				(max_width 2)
				(curved_edges yes)
				(filter_ratio 0.9)
				(enabled yes)
				(allow_two_segments yes)
				(prefer_zone_connections yes)
			)
		)
		(pad "J8" smd circle
			(at 1.5 2.5 270)
			(size 0.5 0.5)
			(layers "F.Cu" "F.Mask" "F.Paste")
			(net 672 "/2xSFP+/KR to SFI #2/MDC")
			(pinfunction "MDC")
			(pintype "input")
			(solder_mask_margin 0.05)
			(teardrops
				(best_length_ratio 0.4)
				(max_length 1)
				(best_width_ratio 0.9)
				(max_width 2)
				(curved_edges yes)
				(filter_ratio 0.9)
				(enabled yes)
				(allow_two_segments yes)
				(prefer_zone_connections yes)
			)
		)
		(pad "J9" smd circle
			(at 2.5 2.5 270)
			(size 0.5 0.5)
			(layers "F.Cu" "F.Mask" "F.Paste")
			(net 747 "Net-(U45C-PRBS_{PASS})")
			(pinfunction "PRBS_{PASS}")
			(pintype "output")
			(solder_mask_margin 0.05)
			(teardrops
				(best_length_ratio 0.4)
				(max_length 1)
				(best_width_ratio 0.9)
				(max_width 2)
				(curved_edges yes)
				(filter_ratio 0.9)
				(enabled yes)
				(allow_two_segments yes)
				(prefer_zone_connections yes)
			)
		)
		(pad "J10" smd circle
			(at 3.5 2.5 270)
			(size 0.5 0.5)
			(layers "F.Cu" "F.Mask" "F.Paste")
			(net 675 "Net-(U45C-GPI0)")
			(pinfunction "GPI0")
			(pintype "input")
			(solder_mask_margin 0.05)
			(teardrops
				(best_length_ratio 0.4)
				(max_length 1)
				(best_width_ratio 0.9)
				(max_width 2)
				(curved_edges yes)
				(filter_ratio 0.9)
				(enabled yes)
				(allow_two_segments yes)
				(prefer_zone_connections yes)
			)
		)
		(pad "J11" smd circle
			(at 4.5 2.5 270)
			(size 0.5 0.5)
			(layers "F.Cu" "F.Mask" "F.Paste")
			(net 78 "+1V8")
			(pinfunction "VDDRB_{LS/HS}")
			(pintype "power_in")
			(solder_mask_margin 0.05)
			(teardrops
				(best_length_ratio 0.4)
				(max_length 1)
				(best_width_ratio 0.9)
				(max_width 2)
				(curved_edges yes)
				(filter_ratio 0.9)
				(enabled yes)
				(allow_two_segments yes)
				(prefer_zone_connections yes)
			)
		)
		(pad "J12" smd circle
			(at 5.5 2.5 270)
			(size 0.5 0.5)
			(layers "F.Cu" "F.Mask" "F.Paste")
			(net 1 "GND")
			(pinfunction "GND")
			(pintype "passive")
			(solder_mask_margin 0.05)
			(teardrops
				(best_length_ratio 0.4)
				(max_length 1)
				(best_width_ratio 0.9)
				(max_width 2)
				(curved_edges yes)
				(filter_ratio 0.9)
				(enabled yes)
				(allow_two_segments yes)
				(prefer_zone_connections yes)
			)
		)
		(pad "K1" smd circle
			(at -5.5 3.5 270)
			(size 0.5 0.5)
			(layers "F.Cu" "F.Mask" "F.Paste")
			(net 1 "GND")
			(pinfunction "GND")
			(pintype "passive")
			(solder_mask_margin 0.05)
			(teardrops
				(best_length_ratio 0.4)
				(max_length 1)
				(best_width_ratio 0.9)
				(max_width 2)
				(curved_edges yes)
				(filter_ratio 0.9)
				(enabled yes)
				(allow_two_segments yes)
				(prefer_zone_connections yes)
			)
		)
		(pad "K2" smd circle
			(at -4.5 3.5 270)
			(size 0.5 0.5)
			(layers "F.Cu" "F.Mask" "F.Paste")
			(net 852 "unconnected-(U45B-INB1+-PadK2)")
			(pinfunction "INB1+")
			(pintype "input+no_connect")
			(solder_mask_margin 0.05)
			(teardrops
				(best_length_ratio 0.4)
				(max_length 1)
				(best_width_ratio 0.9)
				(max_width 2)
				(curved_edges yes)
				(filter_ratio 0.9)
				(enabled yes)
				(allow_two_segments yes)
				(prefer_zone_connections yes)
			)
		)
		(pad "K3" smd circle
			(at -3.5 3.5 270)
			(size 0.5 0.5)
			(layers "F.Cu" "F.Mask" "F.Paste")
			(net 78 "+1V8")
			(pinfunction "VDDRB_{LS/HS}")
			(pintype "passive")
			(solder_mask_margin 0.05)
			(teardrops
				(best_length_ratio 0.4)
				(max_length 1)
				(best_width_ratio 0.9)
				(max_width 2)
				(curved_edges yes)
				(filter_ratio 0.9)
				(enabled yes)
				(allow_two_segments yes)
				(prefer_zone_connections yes)
			)
		)
		(pad "K4" smd circle
			(at -2.5 3.5 270)
			(size 0.5 0.5)
			(layers "F.Cu" "F.Mask" "F.Paste")
			(net 853 "unconnected-(U45B-OUTB1--PadK4)")
			(pinfunction "OUTB1-")
			(pintype "output+no_connect")
			(solder_mask_margin 0.05)
			(teardrops
				(best_length_ratio 0.4)
				(max_length 1)
				(best_width_ratio 0.9)
				(max_width 2)
				(curved_edges yes)
				(filter_ratio 0.9)
				(enabled yes)
				(allow_two_segments yes)
				(prefer_zone_connections yes)
			)
		)
		(pad "K5" smd circle
			(at -1.5 3.5 270)
			(size 0.5 0.5)
			(layers "F.Cu" "F.Mask" "F.Paste")
			(net 854 "unconnected-(U45B-OUTB1+-PadK5)")
			(pinfunction "OUTB1+")
			(pintype "output+no_connect")
			(solder_mask_margin 0.05)
			(teardrops
				(best_length_ratio 0.4)
				(max_length 1)
				(best_width_ratio 0.9)
				(max_width 2)
				(curved_edges yes)
				(filter_ratio 0.9)
				(enabled yes)
				(allow_two_segments yes)
				(prefer_zone_connections yes)
			)
		)
		(pad "K6" smd circle
			(at -0.5 3.5 270)
			(size 0.5 0.5)
			(layers "F.Cu" "F.Mask" "F.Paste")
			(net 1 "GND")
			(pinfunction "GND")
			(pintype "passive")
			(solder_mask_margin 0.05)
			(teardrops
				(best_length_ratio 0.4)
				(max_length 1)
				(best_width_ratio 0.9)
				(max_width 2)
				(curved_edges yes)
				(filter_ratio 0.9)
				(enabled yes)
				(allow_two_segments yes)
				(prefer_zone_connections yes)
			)
		)
		(pad "K7" smd circle
			(at 0.5 3.5 270)
			(size 0.5 0.5)
			(layers "F.Cu" "F.Mask" "F.Paste")
			(net 74 "+1V0")
			(pinfunction "VDDO1")
			(pintype "power_in")
			(solder_mask_margin 0.05)
			(teardrops
				(best_length_ratio 0.4)
				(max_length 1)
				(best_width_ratio 0.9)
				(max_width 2)
				(curved_edges yes)
				(filter_ratio 0.9)
				(enabled yes)
				(allow_two_segments yes)
				(prefer_zone_connections yes)
			)
		)
		(pad "K8" smd circle
			(at 1.5 3.5 270)
			(size 0.5 0.5)
			(layers "F.Cu" "F.Mask" "F.Paste")
			(net 757 "Net-(U45B-LOSB)")
			(pinfunction "LOSB")
			(pintype "output")
			(solder_mask_margin 0.05)
			(teardrops
				(best_length_ratio 0.4)
				(max_length 1)
				(best_width_ratio 0.9)
				(max_width 2)
				(curved_edges yes)
				(filter_ratio 0.9)
				(enabled yes)
				(allow_two_segments yes)
				(prefer_zone_connections yes)
			)
		)
		(pad "K9" smd circle
			(at 2.5 3.5 270)
			(size 0.5 0.5)
			(layers "F.Cu" "F.Mask" "F.Paste")
			(net 740 "Net-(U45C-REFCLK1+)")
			(pinfunction "REFCLK1+")
			(pintype "input")
			(solder_mask_margin 0.05)
			(teardrops
				(best_length_ratio 0.4)
				(max_length 1)
				(best_width_ratio 0.9)
				(max_width 2)
				(curved_edges yes)
				(filter_ratio 0.9)
				(enabled yes)
				(allow_two_segments yes)
				(prefer_zone_connections yes)
			)
		)
		(pad "K10" smd circle
			(at 3.5 3.5 270)
			(size 0.5 0.5)
			(layers "F.Cu" "F.Mask" "F.Paste")
			(net 741 "Net-(U45C-REFCLK1-)")
			(pinfunction "REFCLK1-")
			(pintype "input")
			(solder_mask_margin 0.05)
			(teardrops
				(best_length_ratio 0.4)
				(max_length 1)
				(best_width_ratio 0.9)
				(max_width 2)
				(curved_edges yes)
				(filter_ratio 0.9)
				(enabled yes)
				(allow_two_segments yes)
				(prefer_zone_connections yes)
			)
		)
	)
)
